(kicad_pcb
	(version 20260206)
	(generator "pcbnew")
	(generator_version "10.0")
	(general
		(thickness 1.6)
		(legacy_teardrops no)
	)
	(paper "A4")
	(title_block
		(title "v1-chassis-manager — T6M_CM_d_v01_1031_1645.brd")
		(comment 1 "Open CloudServer (Microsoft) / footprints 1915-1924 of 2512")
	)
	(layers
		(0 "F.Cu" signal "TOP")
		(4 "In1.Cu" signal "GND1")
		(6 "In2.Cu" signal "IN1")
		(8 "In3.Cu" signal "VCC1")
		(10 "In4.Cu" signal "VCC2")
		(12 "In5.Cu" signal "GND2")
		(14 "In6.Cu" signal "IN2")
		(16 "In7.Cu" signal "IN3")
		(18 "In8.Cu" signal "GND3")
		(2 "B.Cu" signal "BOTTOM")
		(9 "F.Adhes" user "F.Adhesive")
		(11 "B.Adhes" user "B.Adhesive")
		(13 "F.Paste" user "Package Geometry/Pastemask Top")
		(15 "B.Paste" user "Package Geometry/Pastemask Bottom")
		(5 "F.SilkS" user "Ref Des/Silkscreen Top")
		(7 "B.SilkS" user "Ref Des/Silkscreen Bottom")
		(1 "F.Mask" user "Board Geometry/Soldermask Top")
		(3 "B.Mask" user "Board Geometry/Soldermask Bottom")
		(17 "Dwgs.User" user "User.Drawings")
		(19 "Cmts.User" user "User.Comments")
		(21 "Eco1.User" user "User.Eco1")
		(23 "Eco2.User" user "User.Eco2")
		(25 "Edge.Cuts" user "Board Geometry/Outline")
		(27 "Margin" user)
		(31 "F.CrtYd" user "Package Geometry/Place Bound Top")
		(29 "B.CrtYd" user "Package Geometry/Place Bound Bottom")
		(35 "F.Fab" user "Ref Des/Assembly Top")
		(33 "B.Fab" user "Ref Des/Assembly Bottom")
	)
	(footprint ""
		(layer "B.Cu")
		(at 90.81262 -163.87445)
		(property "Reference" "R780"
			(at 24.774144 20.136104 0)
			(unlocked yes)
			(layer "B.SilkS")
			(effects
				(font
					(size 0.7874 0.5842)
					(thickness 0.1524)
				)
				(justify left mirror)
			)
		)
		(property "Value" ""
			(at 0 0 0)
			(layer "B.Fab")
			(effects
				(font
					(size 1.27 1.27)
				)
				(justify mirror)
			)
		)
		(duplicate_pad_numbers_are_jumpers no)
		(fp_line
			(start -0.7874 -0.4064)
			(end -0.7874 0.4064)
			(stroke
				(width 0.1524)
				(type default)
			)
			(layer "B.SilkS")
		)
		(fp_line
			(start -0.7874 0.4064)
			(end 0.7874 0.4064)
			(stroke
				(width 0.1524)
				(type default)
			)
			(layer "B.SilkS")
		)
		(fp_line
			(start 0.7874 -0.4064)
			(end -0.7874 -0.4064)
			(stroke
				(width 0.1524)
				(type default)
			)
			(layer "B.SilkS")
		)
		(fp_line
			(start 0.7874 0.4064)
			(end 0.7874 -0.4064)
			(stroke
				(width 0.1524)
				(type default)
			)
			(layer "B.SilkS")
		)
		(fp_poly
			(pts
				(xy 0.508 0.2794) (xy 0.508 0.2286) (xy 0.635 0.2286) (xy 0.635 -0.254) (xy 0.5334 -0.254) (xy 0.5334 -0.2794)
				(xy -0.5334 -0.2794) (xy -0.5334 -0.254) (xy -0.635 -0.254) (xy -0.635 0.254) (xy -0.5334 0.254)
				(xy -0.5334 0.2794)
			)
			(stroke
				(width 0)
				(type default)
			)
			(fill no)
			(layer "B.CrtYd")
		)
		(pad "1" smd rect
			(at -0.40005 0 180)
			(size 0.4572 0.508)
			(layers "B.Cu" "B.Mask" "B.Paste")
			(net "I2C_SDC_SDA")
		)
		(pad "2" smd rect
			(at 0.40005 0 180)
			(size 0.4572 0.508)
			(layers "B.Cu" "B.Mask" "B.Paste")
			(net "P3V3_NODE1")
		)
	)
	(footprint ""
		(layer "B.Cu")
		(at 137.1854 -54.8894)
		(property "Reference" "C598"
			(at 1.7272 -1.82753 0)
			(unlocked yes)
			(layer "B.SilkS")
			(effects
				(font
					(size 0.7874 0.5842)
					(thickness 0.1524)
				)
				(justify left mirror)
			)
		)
		(property "Value" ""
			(at 0 0 0)
			(layer "B.Fab")
			(effects
				(font
					(size 1.27 1.27)
				)
				(justify mirror)
			)
		)
		(duplicate_pad_numbers_are_jumpers no)
		(fp_line
			(start -0.7874 -0.4064)
			(end -0.7874 0.4064)
			(stroke
				(width 0.1524)
				(type default)
			)
			(layer "B.SilkS")
		)
		(fp_line
			(start -0.7874 0.4064)
			(end 0.7874 0.4064)
			(stroke
				(width 0.1524)
				(type default)
			)
			(layer "B.SilkS")
		)
		(fp_line
			(start 0 0.381)
			(end 0 -0.381)
			(stroke
				(width 0.1524)
				(type default)
			)
			(layer "B.SilkS")
		)
		(fp_line
			(start 0.7874 -0.4064)
			(end -0.7874 -0.4064)
			(stroke
				(width 0.1524)
				(type default)
			)
			(layer "B.SilkS")
		)
		(fp_line
			(start 0.7874 0.4064)
			(end 0.7874 -0.4064)
			(stroke
				(width 0.1524)
				(type default)
			)
			(layer "B.SilkS")
		)
		(fp_poly
			(pts
				(xy 0.5334 0.254) (xy 0.635 0.254) (xy 0.635 0.2286) (xy 0.635 -0.254) (xy 0.5334 -0.254) (xy 0.5334 -0.2794)
				(xy -0.5334 -0.2794) (xy -0.5334 -0.254) (xy -0.635 -0.254) (xy -0.635 0.254) (xy -0.5334 0.254)
				(xy -0.5334 0.2794) (xy 0.508 0.2794) (xy 0.5334 0.2794)
			)
			(stroke
				(width 0)
				(type default)
			)
			(fill no)
			(layer "B.CrtYd")
		)
		(pad "1" smd rect
			(at -0.40005 0 180)
			(size 0.4572 0.508)
			(layers "B.Cu" "B.Mask" "B.Paste")
			(net "P3V3_NODE1")
		)
		(pad "2" smd rect
			(at 0.40005 0 180)
			(size 0.4572 0.508)
			(layers "B.Cu" "B.Mask" "B.Paste")
			(net "GND")
		)
	)
	(footprint ""
		(layer "B.Cu")
		(at 43.82262 -159.16529 -90)
		(property "Reference" "C425"
			(at -7.08787 6.84276 270)
			(unlocked yes)
			(layer "B.SilkS")
			(effects
				(font
					(size 0.7874 0.5842)
					(thickness 0.1524)
				)
				(justify left mirror)
			)
		)
		(property "Value" ""
			(at 0 0 90)
			(layer "B.Fab")
			(effects
				(font
					(size 1.27 1.27)
				)
				(justify mirror)
			)
		)
		(duplicate_pad_numbers_are_jumpers no)
		(fp_line
			(start -0.7874 0.4064)
			(end 0.7874 0.4064)
			(stroke
				(width 0.1524)
				(type default)
			)
			(layer "B.SilkS")
		)
		(fp_line
			(start 0.7874 0.4064)
			(end 0.7874 -0.4064)
			(stroke
				(width 0.1524)
				(type default)
			)
			(layer "B.SilkS")
		)
		(fp_line
			(start 0 0.381)
			(end 0 -0.381)
			(stroke
				(width 0.1524)
				(type default)
			)
			(layer "B.SilkS")
		)
		(fp_line
			(start -0.7874 -0.4064)
			(end -0.7874 0.4064)
			(stroke
				(width 0.1524)
				(type default)
			)
			(layer "B.SilkS")
		)
		(fp_line
			(start 0.7874 -0.4064)
			(end -0.7874 -0.4064)
			(stroke
				(width 0.1524)
				(type default)
			)
			(layer "B.SilkS")
		)
		(fp_poly
			(pts
				(xy 0.5334 0.254) (xy 0.635 0.254) (xy 0.635 0.2286) (xy 0.635 -0.254) (xy 0.5334 -0.254) (xy 0.5334 -0.2794)
				(xy -0.5334 -0.2794) (xy -0.5334 -0.254) (xy -0.635 -0.254) (xy -0.635 0.254) (xy -0.5334 0.254)
				(xy -0.5334 0.2794) (xy 0.508 0.2794) (xy 0.5334 0.2794)
			)
			(stroke
				(width 0)
				(type default)
			)
			(fill no)
			(layer "B.CrtYd")
		)
		(pad "1" smd rect
			(at -0.40005 0 90)
			(size 0.4572 0.508)
			(layers "B.Cu" "B.Mask" "B.Paste")
			(net "P1V9_LAN1")
		)
		(pad "2" smd rect
			(at 0.40005 0 90)
			(size 0.4572 0.508)
			(layers "B.Cu" "B.Mask" "B.Paste")
			(net "GND")
		)
	)
	(footprint ""
		(layer "B.Cu")
		(at 62.537086 -140.246862 90)
		(property "Reference" "C294"
			(at -54.2163 -41.487852 270)
			(unlocked yes)
			(layer "B.SilkS")
			(effects
				(font
					(size 0.7874 0.5842)
					(thickness 0.1524)
				)
				(justify left mirror)
			)
		)
		(property "Value" ""
			(at 0 0 90)
			(layer "B.Fab")
			(effects
				(font
					(size 1.27 1.27)
				)
				(justify mirror)
			)
		)
		(duplicate_pad_numbers_are_jumpers no)
		(fp_line
			(start 0.7874 -0.4064)
			(end -0.7874 -0.4064)
			(stroke
				(width 0.1524)
				(type default)
			)
			(layer "B.SilkS")
		)
		(fp_line
			(start -0.7874 -0.4064)
			(end -0.7874 0.4064)
			(stroke
				(width 0.1524)
				(type default)
			)
			(layer "B.SilkS")
		)
		(fp_line
			(start 0 0.381)
			(end 0 -0.381)
			(stroke
				(width 0.1524)
				(type default)
			)
			(layer "B.SilkS")
		)
		(fp_line
			(start 0.7874 0.4064)
			(end 0.7874 -0.4064)
			(stroke
				(width 0.1524)
				(type default)
			)
			(layer "B.SilkS")
		)
		(fp_line
			(start -0.7874 0.4064)
			(end 0.7874 0.4064)
			(stroke
				(width 0.1524)
				(type default)
			)
			(layer "B.SilkS")
		)
		(fp_poly
			(pts
				(xy 0.5334 0.254) (xy 0.635 0.254) (xy 0.635 0.2286) (xy 0.635 -0.254) (xy 0.5334 -0.254) (xy 0.5334 -0.2794)
				(xy -0.5334 -0.2794) (xy -0.5334 -0.254) (xy -0.635 -0.254) (xy -0.635 0.254) (xy -0.5334 0.254)
				(xy -0.5334 0.2794) (xy 0.508 0.2794) (xy 0.5334 0.2794)
			)
			(stroke
				(width 0)
				(type default)
			)
			(fill no)
			(layer "B.CrtYd")
		)
		(pad "1" smd rect
			(at -0.40005 0 270)
			(size 0.4572 0.508)
			(layers "B.Cu" "B.Mask" "B.Paste")
			(net "P1V26_BMC_NODE1")
		)
		(pad "2" smd rect
			(at 0.40005 0 270)
			(size 0.4572 0.508)
			(layers "B.Cu" "B.Mask" "B.Paste")
			(net "GND")
		)
	)
	(footprint ""
		(layer "B.Cu")
		(at 68.48475 -25.873456 -90)
		(property "Reference" "C170"
			(at 0.370332 -1.06426 270)
			(unlocked yes)
			(layer "B.SilkS")
			(effects
				(font
					(size 0.7874 0.5842)
					(thickness 0.1524)
				)
				(justify left mirror)
			)
		)
		(property "Value" ""
			(at 0 0 90)
			(layer "B.Fab")
			(effects
				(font
					(size 1.27 1.27)
				)
				(justify mirror)
			)
		)
		(duplicate_pad_numbers_are_jumpers no)
		(fp_line
			(start -0.7874 0.4064)
			(end 0.7874 0.4064)
			(stroke
				(width 0.1524)
				(type default)
			)
			(layer "B.SilkS")
		)
		(fp_line
			(start 0.7874 0.4064)
			(end 0.7874 -0.4064)
			(stroke
				(width 0.1524)
				(type default)
			)
			(layer "B.SilkS")
		)
		(fp_line
			(start 0 0.381)
			(end 0 -0.381)
			(stroke
				(width 0.1524)
				(type default)
			)
			(layer "B.SilkS")
		)
		(fp_line
			(start -0.7874 -0.4064)
			(end -0.7874 0.4064)
			(stroke
				(width 0.1524)
				(type default)
			)
			(layer "B.SilkS")
		)
		(fp_line
			(start 0.7874 -0.4064)
			(end -0.7874 -0.4064)
			(stroke
				(width 0.1524)
				(type default)
			)
			(layer "B.SilkS")
		)
		(fp_poly
			(pts
				(xy 0.5334 0.254) (xy 0.635 0.254) (xy 0.635 0.2286) (xy 0.635 -0.254) (xy 0.5334 -0.254) (xy 0.5334 -0.2794)
				(xy -0.5334 -0.2794) (xy -0.5334 -0.254) (xy -0.635 -0.254) (xy -0.635 0.254) (xy -0.5334 0.254)
				(xy -0.5334 0.2794) (xy 0.508 0.2794) (xy 0.5334 0.2794)
			)
			(stroke
				(width 0)
				(type default)
			)
			(fill no)
			(layer "B.CrtYd")
		)
		(pad "1" smd rect
			(at -0.40005 0 90)
			(size 0.4572 0.508)
			(layers "B.Cu" "B.Mask" "B.Paste")
			(net "PV_VDDR_NODE1")
		)
		(pad "2" smd rect
			(at 0.40005 0 90)
			(size 0.4572 0.508)
			(layers "B.Cu" "B.Mask" "B.Paste")
			(net "GND")
		)
	)
	(footprint ""
		(layer "B.Cu")
		(at 61.326522 -130.924046)
		(property "Reference" "C268"
			(at -40.553132 52.957984 0)
			(unlocked yes)
			(layer "B.SilkS")
			(effects
				(font
					(size 0.7874 0.5842)
					(thickness 0.1524)
				)
				(justify left mirror)
			)
		)
		(property "Value" ""
			(at 0 0 0)
			(layer "B.Fab")
			(effects
				(font
					(size 1.27 1.27)
				)
				(justify mirror)
			)
		)
		(duplicate_pad_numbers_are_jumpers no)
		(fp_line
			(start -0.7874 -0.4064)
			(end -0.7874 0.4064)
			(stroke
				(width 0.1524)
				(type default)
			)
			(layer "B.SilkS")
		)
		(fp_line
			(start -0.7874 0.4064)
			(end 0.7874 0.4064)
			(stroke
				(width 0.1524)
				(type default)
			)
			(layer "B.SilkS")
		)
		(fp_line
			(start 0 0.381)
			(end 0 -0.381)
			(stroke
				(width 0.1524)
				(type default)
			)
			(layer "B.SilkS")
		)
		(fp_line
			(start 0.7874 -0.4064)
			(end -0.7874 -0.4064)
			(stroke
				(width 0.1524)
				(type default)
			)
			(layer "B.SilkS")
		)
		(fp_line
			(start 0.7874 0.4064)
			(end 0.7874 -0.4064)
			(stroke
				(width 0.1524)
				(type default)
			)
			(layer "B.SilkS")
		)
		(fp_poly
			(pts
				(xy 0.5334 0.254) (xy 0.635 0.254) (xy 0.635 0.2286) (xy 0.635 -0.254) (xy 0.5334 -0.254) (xy 0.5334 -0.2794)
				(xy -0.5334 -0.2794) (xy -0.5334 -0.254) (xy -0.635 -0.254) (xy -0.635 0.254) (xy -0.5334 0.254)
				(xy -0.5334 0.2794) (xy 0.508 0.2794) (xy 0.5334 0.2794)
			)
			(stroke
				(width 0)
				(type default)
			)
			(fill no)
			(layer "B.CrtYd")
		)
		(pad "1" smd rect
			(at -0.40005 0 180)
			(size 0.4572 0.508)
			(layers "B.Cu" "B.Mask" "B.Paste")
			(net "BMC_NODE1_HPLLAV33")
		)
		(pad "2" smd rect
			(at 0.40005 0 180)
			(size 0.4572 0.508)
			(layers "B.Cu" "B.Mask" "B.Paste")
			(net "GND")
		)
	)
	(footprint ""
		(layer "B.Cu")
		(at 131.784852 -135.87095 -90)
		(property "Reference" "C893"
			(at 5.07365 -0.25781 270)
			(unlocked yes)
			(layer "B.SilkS")
			(effects
				(font
					(size 0.7874 0.5842)
					(thickness 0.1524)
				)
				(justify left mirror)
			)
		)
		(property "Value" ""
			(at 0 0 90)
			(layer "B.Fab")
			(effects
				(font
					(size 1.27 1.27)
				)
				(justify mirror)
			)
		)
		(duplicate_pad_numbers_are_jumpers no)
		(fp_line
			(start -0.7874 0.4064)
			(end 0.7874 0.4064)
			(stroke
				(width 0.1524)
				(type default)
			)
			(layer "B.SilkS")
		)
		(fp_line
			(start 0.7874 0.4064)
			(end 0.7874 -0.4064)
			(stroke
				(width 0.1524)
				(type default)
			)
			(layer "B.SilkS")
		)
		(fp_line
			(start 0 0.381)
			(end 0 -0.381)
			(stroke
				(width 0.1524)
				(type default)
			)
			(layer "B.SilkS")
		)
		(fp_line
			(start -0.7874 -0.4064)
			(end -0.7874 0.4064)
			(stroke
				(width 0.1524)
				(type default)
			)
			(layer "B.SilkS")
		)
		(fp_line
			(start 0.7874 -0.4064)
			(end -0.7874 -0.4064)
			(stroke
				(width 0.1524)
				(type default)
			)
			(layer "B.SilkS")
		)
		(fp_poly
			(pts
				(xy 0.5334 0.254) (xy 0.635 0.254) (xy 0.635 0.2286) (xy 0.635 -0.254) (xy 0.5334 -0.254) (xy 0.5334 -0.2794)
				(xy -0.5334 -0.2794) (xy -0.5334 -0.254) (xy -0.635 -0.254) (xy -0.635 0.254) (xy -0.5334 0.254)
				(xy -0.5334 0.2794) (xy 0.508 0.2794) (xy 0.5334 0.2794)
			)
			(stroke
				(width 0)
				(type default)
			)
			(fill no)
			(layer "B.CrtYd")
		)
		(pad "1" smd rect
			(at -0.40005 0 90)
			(size 0.4572 0.508)
			(layers "B.Cu" "B.Mask" "B.Paste")
			(net "P1V538_BMC_NODE1")
		)
		(pad "2" smd rect
			(at 0.40005 0 90)
			(size 0.4572 0.508)
			(layers "B.Cu" "B.Mask" "B.Paste")
			(net "GND")
		)
	)
	(footprint ""
		(layer "B.Cu")
		(at 61.766196 -96.824038)
		(property "Reference" "R63"
			(at -4.06654 -7.642352 0)
			(unlocked yes)
			(layer "B.SilkS")
			(effects
				(font
					(size 0.7874 0.5842)
					(thickness 0.1524)
				)
				(justify left mirror)
			)
		)
		(property "Value" ""
			(at 0 0 0)
			(layer "B.Fab")
			(effects
				(font
					(size 1.27 1.27)
				)
				(justify mirror)
			)
		)
		(duplicate_pad_numbers_are_jumpers no)
		(fp_line
			(start -0.7874 -0.4064)
			(end -0.7874 0.4064)
			(stroke
				(width 0.1524)
				(type default)
			)
			(layer "B.SilkS")
		)
		(fp_line
			(start -0.7874 0.4064)
			(end 0.7874 0.4064)
			(stroke
				(width 0.1524)
				(type default)
			)
			(layer "B.SilkS")
		)
		(fp_line
			(start 0.7874 -0.4064)
			(end -0.7874 -0.4064)
			(stroke
				(width 0.1524)
				(type default)
			)
			(layer "B.SilkS")
		)
		(fp_line
			(start 0.7874 0.4064)
			(end 0.7874 -0.4064)
			(stroke
				(width 0.1524)
				(type default)
			)
			(layer "B.SilkS")
		)
		(fp_poly
			(pts
				(xy 0.508 0.2794) (xy 0.508 0.2286) (xy 0.635 0.2286) (xy 0.635 -0.254) (xy 0.5334 -0.254) (xy 0.5334 -0.2794)
				(xy -0.5334 -0.2794) (xy -0.5334 -0.254) (xy -0.635 -0.254) (xy -0.635 0.254) (xy -0.5334 0.254)
				(xy -0.5334 0.2794)
			)
			(stroke
				(width 0)
				(type default)
			)
			(fill no)
			(layer "B.CrtYd")
		)
		(pad "1" smd rect
			(at -0.40005 0 180)
			(size 0.4572 0.508)
			(layers "B.Cu" "B.Mask" "B.Paste")
			(net "LPC_CPU_NODE1_LAD0")
		)
		(pad "2" smd rect
			(at 0.40005 0 180)
			(size 0.4572 0.508)
			(layers "B.Cu" "B.Mask" "B.Paste")
			(net "LPC_CPU_NODE1_LAD0_R")
		)
	)
	(footprint ""
		(layer "B.Cu")
		(at 138.627866 -104.55148 180)
		(property "Reference" "R1"
			(at -0.609346 1.29413 0)
			(unlocked yes)
			(layer "B.SilkS")
			(effects
				(font
					(size 0.7874 0.5842)
					(thickness 0.1524)
				)
				(justify mirror)
			)
		)
		(property "Value" ""
			(at 0 0 0)
			(layer "B.Fab")
			(effects
				(font
					(size 1.27 1.27)
				)
				(justify mirror)
			)
		)
		(duplicate_pad_numbers_are_jumpers no)
		(fp_line
			(start 1.2954 0.5842)
			(end 1.2954 -0.5842)
			(stroke
				(width 0.1524)
				(type default)
			)
			(layer "B.SilkS")
		)
		(fp_line
			(start 1.2954 -0.5842)
			(end -1.2954 -0.5842)
			(stroke
				(width 0.1524)
				(type default)
			)
			(layer "B.SilkS")
		)
		(fp_line
			(start -1.2954 0.5842)
			(end 1.2954 0.5842)
			(stroke
				(width 0.1524)
				(type default)
			)
			(layer "B.SilkS")
		)
		(fp_line
			(start -1.2954 -0.5842)
			(end -1.2954 0.5842)
			(stroke
				(width 0.1524)
				(type default)
			)
			(layer "B.SilkS")
		)
		(fp_poly
			(pts
				(xy -1.143 -0.3556) (xy -1.143 0.3556) (xy -0.8636 0.3556) (xy -0.8636 0.4572) (xy 0.8636 0.4572)
				(xy 0.8636 0.4318) (xy 0.8636 0.3556) (xy 1.143 0.3556) (xy 1.143 -0.3556) (xy 0.8636 -0.3556) (xy 0.8636 -0.4572)
				(xy -0.8636 -0.4572) (xy -0.8636 -0.3556)
			)
			(stroke
				(width 0)
				(type default)
			)
			(fill no)
			(layer "B.CrtYd")
		)
		(pad "1" smd rect
			(at -0.7366 0 270)
			(size 0.7112 0.8128)
			(layers "B.Cu" "B.Mask" "B.Paste")
			(net "P3V3_NODE1")
		)
		(pad "2" smd rect
			(at 0.7366 0 270)
			(size 0.7112 0.8128)
			(layers "B.Cu" "B.Mask" "B.Paste")
			(net "P3V3_CLK_NODE1_R")
		)
	)
	(footprint ""
		(layer "B.Cu")
		(at 180.16093 -118.90502)
		(property "Reference" "C782"
			(at 2.877566 -0.147066 0)
			(unlocked yes)
			(layer "B.SilkS")
			(effects
				(font
					(size 0.7874 0.5842)
					(thickness 0.1524)
				)
				(justify mirror)
			)
		)
		(property "Value" ""
			(at 0 0 0)
			(layer "B.Fab")
			(effects
				(font
					(size 1.27 1.27)
				)
				(justify mirror)
			)
		)
		(duplicate_pad_numbers_are_jumpers no)
		(fp_line
			(start -1.2954 -0.5842)
			(end -1.2954 0.5842)
			(stroke
				(width 0.1524)
				(type default)
			)
			(layer "B.SilkS")
		)
		(fp_line
			(start -1.2954 0.5842)
			(end 1.2954 0.5842)
			(stroke
				(width 0.1524)
				(type default)
			)
			(layer "B.SilkS")
		)
		(fp_line
			(start 0 -0.5842)
			(end 0 0.5842)
			(stroke
				(width 0.1524)
				(type default)
			)
			(layer "B.SilkS")
		)
		(fp_line
			(start 1.2954 -0.5842)
			(end -1.2954 -0.5842)
			(stroke
				(width 0.1524)
				(type default)
			)
			(layer "B.SilkS")
		)
		(fp_line
			(start 1.2954 0.5842)
			(end 1.2954 -0.5842)
			(stroke
				(width 0.1524)
				(type default)
			)
			(layer "B.SilkS")
		)
		(fp_poly
			(pts
				(xy -0.8636 -0.4572) (xy -0.8636 -0.3556) (xy -1.143 -0.3556) (xy -1.143 0.3556) (xy -0.8636 0.3556)
				(xy -0.8636 0.4572) (xy 0.8636 0.4572) (xy 0.8636 0.3556) (xy 1.143 0.3556) (xy 1.143 -0.3556) (xy 0.8636 -0.3556)
				(xy 0.8636 -0.4572)
			)
			(stroke
				(width 0)
				(type default)
			)
			(fill no)
			(layer "B.CrtYd")
		)
		(fp_line
			(start -0.884936 -0.504952)
			(end -0.884936 0.504952)
			(stroke
				(width 0.1)
				(type default)
			)
			(layer "B.Fab")
		)
		(fp_line
			(start -0.884936 0.504952)
			(end 0.884936 0.504952)
			(stroke
				(width 0.1)
				(type default)
			)
			(layer "B.Fab")
		)
		(fp_line
			(start 0.884936 -0.504952)
			(end -0.884936 -0.504952)
			(stroke
				(width 0.1)
				(type default)
			)
			(layer "B.Fab")
		)
		(fp_line
			(start 0.884936 0.504952)
			(end 0.884936 -0.504952)
			(stroke
				(width 0.1)
				(type default)
			)
			(layer "B.Fab")
		)
		(pad "1" smd rect
			(at -0.7366 0 90)
			(size 0.7112 0.8128)
			(layers "B.Cu" "B.Mask" "B.Paste")
			(net "P3V3_STB_NODE1")
		)
		(pad "2" smd rect
			(at 0.7366 0 90)
			(size 0.7112 0.8128)
			(layers "B.Cu" "B.Mask" "B.Paste")
			(net "GND")
		)
	)
)
